FILE_TYPE = MULTI_PHYS_TABLE;

{TIME=' COMPILATION ON MON JUL 05 19:34:44 2010  ';}

PART 'MOSFET_N'

{==========================================================================================================================================================================================================}
:VALUE             | MANUF_PN    | PACK_TYPE | MATERIAL | PART_NUMBER      = STANDARD         | LIFECYCLE        | PART_NUMBER   | JEDEC_TYPE | CLASS | DESCRIPTION                         | COMPONENT_TYPE | LEAD_LENGTH | LPID | DAY        ;
{======================================================================================================}	
 '2N7002LT1'    | '2N7002LT1'| 'SMLF'       | 'IC'     | 'BAN70020T04'(!) = 'End of Design'  | 'Comp-Approve'   | 'BAN70020T04' |'SOT23_GDS'| 'IC'  | 'TRANSISTOR MOSFET 2N7002(60V,0.115A)' | 'SMALLSMT'     | ''          | ''   | '20100709'	
 '2N7002LT1'    | '2N7002LT1'| 'SMLF'       | 'EMPTY'  | 'BAN70020T04'(!) = 'End of Design'  | 'Comp-Approve'   | 'BAN70020T04' |'SOT23_GDS'| 'IO'  | 'TRANSISTOR MOSFET 2N7002(60V,0.115A)' | 'SMALLSMT'     | ''          | ''   | '20100709'
 '2N7002-T1-E3' | '2N7002-T1-E3'| 'SMLF'    | 'IC'     | 'BAN70020050'(!) = 'End of Design'  | 'Comp-Approve'   | 'BAN70020050' |'SOT23_GDS'| 'IC'  | 'TRANS MOSFET 2N7002-T1-E3(60V,0.115A)' | 'SMALLSMT'     | ''          | ''   | '20100709'	
 '2N7002-T1-E3' | '2N7002-T1-E3'| 'SMLF'    | 'EMPTY'  | 'BAN70020050'(!) = 'End of Design'  | 'Comp-Approve'   | 'BAN70020050' |'SOT23_GDS'| 'IO'  | 'TRANS MOSFET 2N7002-T1-E3(60V,0.115A)' | 'SMALLSMT'     | ''          | ''   | '20100709'
  'BSS138K'      | 'BSS138K'      | 'SMLF'    | 'IC'     | 'BAM138K0000'(!) = 'End of Design'  | 'Comp-Approve'   | 'BAM138K0000' |'SOT23_GDSXD'| 'IC'  | 'TRANS MOS BSS138K(50V,0.22A,0.35W)'    | 'SMALLSMT'     | ''          | ''   | '20150826'
  'BSS138K'      | 'BSS138K'      | 'SMLF'    | 'EMPTY'  | 'BAM138K0000'(!) = 'End of Design'  | 'Comp-Approve'   | 'BAM138K0000' |'SOT23_GDSXD'| 'IO'  | 'TRANS MOS BSS138K(50V,0.22A,0.35W)'    | 'SMALLSMT'     | ''          | ''   | '20150826'

  
END_PART

END.
